# Bill of Materials-GPS_MODULE_ZED-F9T-00B(V1I1).xlsx — Bill of Materials-GPS_MODULE_ZE (bom)
| Description | Designator | Quantity | Supplier Part Number 1 | Supplier 1 | Manufacturer | Manufacturer Part Number | Manufacturer Part Number 1 | Manufacturer 1 |
| CAP, CER, X5R, 1UF, 10%, 25V, 0402, 0.55MM T | C1, C2, C3, C4, C5 | 5 | 490-10017-1-ND | Digikey | Murata | GRM155R61E105KA12D |  |  |
| None | C6, C7, C8, C9 | 4 |  |  |  |  |  |  |
| Chip Multilayer Ceramic Capacitors for General Purpose, 0201, 10000pF, X7R, 15%, 10%, 16V | C10 | 1 |  |  |  |  |  |  |
| TVS DIODE 14V 40V 0402 | D1 | 1 |  |  | Littelfuse Inc. | PESD0402-140 |  |  |
| LED, GREEN, 574NM, 20MA, 20MCD MIN, 2.5VF MAX, 0603, 1.10MM T | DS1, DS2, DS3 | 3 | 67-2320-1-ND | Digikey | Lumex Opto/Components Inc. | SML-LXFM0603SUGCTR |  |  |
| Dual Row 8 Position 2 mm Pitch Surface Mount Header | J1 | 1 | S6009-04-ND | Digi-Key | Sullins | NRPN042MAMS-RC |  |  |
| Rf Coaxial Board Mount Connector | J2 | 1 | J10507-ND | Digi-Key | Bel Cinch | 131-3711-301 |  |  |
| Multilayer type RF Inductor 47nH ±5% 0.72Ω 300mA 0402 | L1 | 1 |  |  |  |  |  |  |
| MOSFET, P-CH, 8VDS, 3.7A ID, 0.052 OHM RDS(ON)@4.5VGS/3.5A, SOT-23-3 | Q1 | 1 | NTR2101PT1GOSCT-ND | Digikey | onsemi | NTR2101PT1G |  |  |
| 1kΩ ±1% 0.063W 0402 Thick Film Chip Resistor AEC-Q200 compliant | R1, R2, R3, R10, R13, R14 | 6 |  |  |  |  |  |  |
| 10kΩ ±1% 0.063W 0402 Thick Film Chip Resistor AEC-Q200 compliant | R4, R7, R8 | 3 |  |  |  |  |  |  |
| 100kΩ ±1% 0.063W 0402 Thick Film Chip Resistor AEC-Q200 compliant | R9, R11 | 2 |  |  |  |  |  |  |
| RES, 25 OHM, 2%, 1.5W, 150PPM/C, 0603 | R12 | 1 | 541-2654-1-ND | Digikey | Vishay | RCP0603W25R0GEB |  |  |
| Multi-band GNSS Receiver with Nanosecond-level Timing Accuracy | U1 | 1 | 672-1197-1-ND | Digi-Key | u-blox | ZED-F9T-00B |  |  |
| Triple Buffer/Driver With Open-Drain Output, DCU0008A, LARGE T&R | U2, U3 | 2 |  |  | Texas Instruments |  |  |  |
| micropower Rail-to-Rail Input and Output Operational Amplifier, 5-pin SC-70, Pb-Free | U4 | 1 |  |  | Texas Instruments |  |  |  |
